FILE_TYPE = CONNECTIVITY;
{Allegro Design Entry HDL 17.4-2019 S026 (4007227) 1/17/2022}
"PAGE_NUMBER" = 6;
0"NC";
END.
